(kicad_pcb
	(version 20241229)
	(generator "pcbnew")
	(generator_version "9.0")
	(general
		(thickness 1.63)
		(legacy_teardrops no)
	)
	(paper "A4")
	(title_block
		(title "CM4 Baseboard")
		(date "2026-01-05")
		(rev "1.1.1")
		(company "Antmicro Ltd")
		(comment 1 "www.antmicro.com")
		(comment 9 "footprints 192-197 of 506")
	)
	(layers
		(0 "F.Cu" signal)
		(4 "In1.Cu" power)
		(6 "In2.Cu" power)
		(8 "In3.Cu" signal)
		(10 "In4.Cu" signal)
		(2 "B.Cu" signal)
		(9 "F.Adhes" user "F.Adhesive")
		(11 "B.Adhes" user "B.Adhesive")
		(13 "F.Paste" user)
		(15 "B.Paste" user)
		(5 "F.SilkS" user "F.Silkscreen")
		(7 "B.SilkS" user "B.Silkscreen")
		(1 "F.Mask" user)
		(3 "B.Mask" user)
		(17 "Dwgs.User" user "User.Drawings")
		(19 "Cmts.User" user "User.Comments")
		(21 "Eco1.User" user "User.Eco1")
		(23 "Eco2.User" user "User.Eco2")
		(25 "Edge.Cuts" user)
		(27 "Margin" user)
		(31 "F.CrtYd" user "F.Courtyard")
		(29 "B.CrtYd" user "B.Courtyard")
		(35 "F.Fab" user)
		(33 "B.Fab" user)
	)
	(footprint "antmicro-footprints:Choke_Murata-DLW21"
		(layer "F.Cu")
		(at 83.992962 122.6665)
		(property "Reference" "T902"
			(at 1.175 0.81 0)
			(layer "F.SilkS")
			(effects
				(font
					(size 0.7 0.7)
					(thickness 0.15)
				)
				(justify left bottom)
			)
		)
		(property "Value" "Choke_DLW21SN900SQ2L"
			(at 0.4 1.778 0)
			(layer "F.Fab")
			(effects
				(font
					(size 0.7 0.7)
					(thickness 0.15)
				)
				(justify left bottom)
			)
		)
		(property "Datasheet" "https://www.murata.com/en-us/products/productdetail?partno=DLW21SN900SQ2%23"
			(at 0 0 0)
			(layer "F.Fab")
			(hide yes)
			(effects
				(font
					(size 1.27 1.27)
					(thickness 0.15)
				)
			)
		)
		(property "Manufacturer" "Murata"
			(at 0 0 0)
			(unlocked yes)
			(layer "F.Fab")
			(hide yes)
			(effects
				(font
					(size 1 1)
					(thickness 0.15)
				)
			)
		)
		(property "MPN" "DLW21SN900SQ2L"
			(at 0 0 0)
			(unlocked yes)
			(layer "F.Fab")
			(hide yes)
			(effects
				(font
					(size 1 1)
					(thickness 0.15)
				)
			)
		)
		(property "IMax" "0.33 A"
			(at 0 0 0)
			(unlocked yes)
			(layer "F.Fab")
			(hide yes)
			(effects
				(font
					(size 1 1)
					(thickness 0.15)
				)
			)
		)
		(property "Author" "Antmicro"
			(at 0 0 0)
			(unlocked yes)
			(layer "F.Fab")
			(hide yes)
			(effects
				(font
					(size 1 1)
					(thickness 0.15)
				)
			)
		)
		(property "License" "Apache-2.0"
			(at 0 0 0)
			(unlocked yes)
			(layer "F.Fab")
			(hide yes)
			(effects
				(font
					(size 1 1)
					(thickness 0.15)
				)
			)
		)
		(property ki_fp_filters "IND_ACM9070_TDK")
		(sheetname "/USB/")
		(sheetfile "usb.kicad_sch")
		(attr smd)
		(fp_line
			(start -1 -0.8)
			(end 1 -0.8)
			(stroke
				(width 0.15)
				(type solid)
			)
			(layer "F.SilkS")
		)
		(fp_line
			(start 1 0.8)
			(end -1 0.8)
			(stroke
				(width 0.15)
				(type solid)
			)
			(layer "F.SilkS")
		)
		(fp_circle
			(center -1.475 0.775)
			(end -1.425 0.775)
			(stroke
				(width 0.15)
				(type solid)
			)
			(fill yes)
			(layer "F.SilkS")
		)
		(fp_rect
			(start -1.55 -0.85)
			(end 1.55 0.85)
			(stroke
				(width 0.05)
				(type solid)
			)
			(fill no)
			(layer "F.CrtYd")
		)
		(fp_line
			(start -1 0.35)
			(end -0.75 0.6)
			(stroke
				(width 0.15)
				(type solid)
			)
			(layer "F.Fab")
		)
		(fp_rect
			(start -1 -0.6)
			(end 1 0.6)
			(stroke
				(width 0.15)
				(type solid)
			)
			(fill no)
			(layer "F.Fab")
		)
		(fp_text user "License: Apache-2.0"
			(at -1.55 6.178 0)
			(layer "F.Fab")
			(effects
				(font
					(size 0.7 0.7)
					(thickness 0.15)
				)
				(justify left bottom)
			)
		)
		(fp_text user "Author: Antmicro"
			(at -1.55 4.978 0)
			(layer "F.Fab")
			(effects
				(font
					(size 0.7 0.7)
					(thickness 0.15)
				)
				(justify left bottom)
			)
		)
		(fp_text user "${REFERENCE}"
			(at -1.55 3.778 0)
			(layer "F.Fab")
			(effects
				(font
					(size 0.7 0.7)
					(thickness 0.15)
				)
				(justify left bottom)
			)
		)
		(pad "1" smd roundrect
			(at -0.85 0.4)
			(size 0.9 0.4)
			(layers "F.Cu" "F.Mask" "F.Paste")
			(roundrect_rratio 0.1)
			(net 209 "/USB/DD_P")
			(pinfunction "1")
			(pintype "passive")
		)
		(pad "2" smd roundrect
			(at 0.85 0.4)
			(size 0.9 0.4)
			(layers "F.Cu" "F.Mask" "F.Paste")
			(roundrect_rratio 0.1)
			(net 278 "/USB/USBD.D_P")
			(pinfunction "2")
			(pintype "passive")
		)
		(pad "3" smd roundrect
			(at 0.85 -0.4)
			(size 0.9 0.4)
			(layers "F.Cu" "F.Mask" "F.Paste")
			(roundrect_rratio 0.1)
			(net 277 "/USB/USBD.D_N")
			(pinfunction "3")
			(pintype "passive")
		)
		(pad "4" smd roundrect
			(at -0.85 -0.4)
			(size 0.9 0.4)
			(layers "F.Cu" "F.Mask" "F.Paste")
			(roundrect_rratio 0.1)
			(net 210 "/USB/DD_N")
			(pinfunction "4")
			(pintype "passive")
		)
	)
	(footprint "antmicro-footprints:R_0402_1005Metric"
		(layer "F.Cu")
		(at 132.937962 161.4965 90)
		(descr "Resistor SMD 0402")
		(tags "resistor SMD 0402")
		(property "Reference" "R605"
			(at -1.23 -1.81 90)
			(layer "F.SilkS")
			(effects
				(font
					(size 0.7 0.7)
					(thickness 0.15)
				)
				(justify left bottom)
			)
		)
		(property "Value" "R_4k7_0402"
			(at -1.011843 1.772047 90)
			(layer "F.Fab")
			(effects
				(font
					(size 0.7 0.7)
					(thickness 0.15)
				)
				(justify left bottom)
			)
		)
		(property "Datasheet" "https://www.bourns.com/docs/product-datasheets/cr.pdf"
			(at 0 0 90)
			(layer "F.Fab")
			(hide yes)
			(effects
				(font
					(size 1.27 1.27)
					(thickness 0.15)
				)
			)
		)
		(property "Manufacturer" "Bourns"
			(at 0 0 90)
			(unlocked yes)
			(layer "F.Fab")
			(hide yes)
			(effects
				(font
					(size 1 1)
					(thickness 0.15)
				)
			)
		)
		(property "MPN" "CR0402-FX-4701GLF"
			(at 0 0 90)
			(unlocked yes)
			(layer "F.Fab")
			(hide yes)
			(effects
				(font
					(size 1 1)
					(thickness 0.15)
				)
			)
		)
		(property "Val" "4k7"
			(at 0 0 90)
			(unlocked yes)
			(layer "F.Fab")
			(hide yes)
			(effects
				(font
					(size 1 1)
					(thickness 0.15)
				)
			)
		)
		(property "License" "Apache-2.0"
			(at 0 0 90)
			(unlocked yes)
			(layer "F.Fab")
			(hide yes)
			(effects
				(font
					(size 1 1)
					(thickness 0.15)
				)
			)
		)
		(property "Author" "Antmicro"
			(at 0 0 90)
			(unlocked yes)
			(layer "F.Fab")
			(hide yes)
			(effects
				(font
					(size 1 1)
					(thickness 0.15)
				)
			)
		)
		(property "Tolerance" "1%"
			(at 0 0 90)
			(unlocked yes)
			(layer "F.Fab")
			(hide yes)
			(effects
				(font
					(size 1 1)
					(thickness 0.15)
				)
			)
		)
		(sheetname "/CSI/")
		(sheetfile "csi.kicad_sch")
		(attr smd)
		(fp_rect
			(start -0.925 -0.47)
			(end 0.925 0.47)
			(stroke
				(width 0.05)
				(type default)
			)
			(fill no)
			(layer "F.CrtYd")
		)
		(fp_rect
			(start -0.5 -0.25)
			(end 0.5 0.25)
			(stroke
				(width 0.15)
				(type solid)
			)
			(fill no)
			(layer "F.Fab")
		)
		(fp_text user "${REFERENCE}"
			(at -0.95 3.168 90)
			(layer "F.Fab")
			(effects
				(font
					(size 0.7 0.7)
					(thickness 0.15)
				)
				(justify left bottom)
			)
		)
		(fp_text user "License: Apache-2.0"
			(at -0.95 5.169 90)
			(layer "F.Fab")
			(effects
				(font
					(size 0.7 0.7)
					(thickness 0.15)
				)
				(justify left bottom)
			)
		)
		(fp_text user "Author: Antmicro"
			(at -0.95 4.169 90)
			(layer "F.Fab")
			(effects
				(font
					(size 0.7 0.7)
					(thickness 0.15)
				)
				(justify left bottom)
			)
		)
		(pad "1" smd roundrect
			(at -0.48 0 90)
			(size 0.59 0.64)
			(layers "F.Cu" "F.Mask" "F.Paste")
			(roundrect_rratio 0.25)
			(net 3 "GND")
			(pintype "passive")
		)
		(pad "2" smd roundrect
			(at 0.48 0 90)
			(size 0.59 0.64)
			(layers "F.Cu" "F.Mask" "F.Paste")
			(roundrect_rratio 0.25)
			(net 373 "Net-(U602-ISET)")
			(pintype "passive")
		)
	)
	(footprint "antmicro-footprints:R_0402_1005Metric"
		(layer "F.Cu")
		(at 46.542962 130.7665)
		(descr "Resistor SMD 0402")
		(tags "resistor SMD 0402")
		(property "Reference" "R402"
			(at -3.975 0.4 0)
			(layer "F.SilkS")
			(effects
				(font
					(size 0.7 0.7)
					(thickness 0.15)
				)
				(justify left bottom)
			)
		)
		(property "Value" "R_49k9_0402"
			(at -1.011843 1.772047 0)
			(layer "F.Fab")
			(effects
				(font
					(size 0.7 0.7)
					(thickness 0.15)
				)
				(justify left bottom)
			)
		)
		(property "Datasheet" "https://www.bourns.com/docs/product-datasheets/cr.pdf"
			(at 0 0 0)
			(layer "F.Fab")
			(hide yes)
			(effects
				(font
					(size 1.27 1.27)
					(thickness 0.15)
				)
			)
		)
		(property "Manufacturer" "Bourns"
			(at 0 0 0)
			(unlocked yes)
			(layer "F.Fab")
			(hide yes)
			(effects
				(font
					(size 1 1)
					(thickness 0.15)
				)
			)
		)
		(property "MPN" "CR0402-FX-4992GLF"
			(at 0 0 0)
			(unlocked yes)
			(layer "F.Fab")
			(hide yes)
			(effects
				(font
					(size 1 1)
					(thickness 0.15)
				)
			)
		)
		(property "Val" "49k9"
			(at 0 0 0)
			(unlocked yes)
			(layer "F.Fab")
			(hide yes)
			(effects
				(font
					(size 1 1)
					(thickness 0.15)
				)
			)
		)
		(property "License" "Apache-2.0"
			(at 0 0 0)
			(unlocked yes)
			(layer "F.Fab")
			(hide yes)
			(effects
				(font
					(size 1 1)
					(thickness 0.15)
				)
			)
		)
		(property "Author" "Antmicro"
			(at 0 0 0)
			(unlocked yes)
			(layer "F.Fab")
			(hide yes)
			(effects
				(font
					(size 1 1)
					(thickness 0.15)
				)
			)
		)
		(property "Tolerance" "1%"
			(at 0 0 0)
			(unlocked yes)
			(layer "F.Fab")
			(hide yes)
			(effects
				(font
					(size 1 1)
					(thickness 0.15)
				)
			)
		)
		(sheetname "/Ethernet/")
		(sheetfile "ethernet.kicad_sch")
		(attr smd)
		(fp_rect
			(start -0.925 -0.47)
			(end 0.925 0.47)
			(stroke
				(width 0.05)
				(type default)
			)
			(fill no)
			(layer "F.CrtYd")
		)
		(fp_rect
			(start -0.5 -0.25)
			(end 0.5 0.25)
			(stroke
				(width 0.15)
				(type solid)
			)
			(fill no)
			(layer "F.Fab")
		)
		(fp_text user "Author: Antmicro"
			(at -0.95 4.169 0)
			(layer "F.Fab")
			(effects
				(font
					(size 0.7 0.7)
					(thickness 0.15)
				)
				(justify left bottom)
			)
		)
		(fp_text user "${REFERENCE}"
			(at -0.95 3.168 0)
			(layer "F.Fab")
			(effects
				(font
					(size 0.7 0.7)
					(thickness 0.15)
				)
				(justify left bottom)
			)
		)
		(fp_text user "License: Apache-2.0"
			(at -0.95 5.169 0)
			(layer "F.Fab")
			(effects
				(font
					(size 0.7 0.7)
					(thickness 0.15)
				)
				(justify left bottom)
			)
		)
		(pad "1" smd roundrect
			(at -0.48 0)
			(size 0.59 0.64)
			(layers "F.Cu" "F.Mask" "F.Paste")
			(roundrect_rratio 0.25)
			(net 90 "/Ethernet/VSS")
			(pintype "passive")
		)
		(pad "2" smd roundrect
			(at 0.48 0)
			(size 0.59 0.64)
			(layers "F.Cu" "F.Mask" "F.Paste")
			(roundrect_rratio 0.25)
			(net 357 "/Ethernet/REF")
			(pintype "passive")
		)
	)
	(footprint "antmicro-footprints:C_0402_1005Metric"
		(layer "F.Cu")
		(at 83.567962 151.1915 90)
		(descr "Capacitor SMD 0402")
		(tags "capacitor SMD 0402")
		(property "Reference" "C207"
			(at -1.105 -0.58 90)
			(layer "F.SilkS")
			(effects
				(font
					(size 0.7 0.7)
					(thickness 0.15)
				)
				(justify left bottom)
			)
		)
		(property "Value" "C_100n_0402"
			(at -1.022927 2.155213 90)
			(layer "F.Fab")
			(effects
				(font
					(size 0.7 0.7)
					(thickness 0.15)
				)
				(justify left bottom)
			)
		)
		(property "Datasheet" "https://www.murata.com/products/productdetail?partno=GRM155R61H104KE14%23"
			(at 0 0 90)
			(layer "F.Fab")
			(hide yes)
			(effects
				(font
					(size 1.27 1.27)
					(thickness 0.15)
				)
			)
		)
		(property "MPN" "GRM155R61H104KE14D"
			(at 0 0 90)
			(unlocked yes)
			(layer "F.Fab")
			(hide yes)
			(effects
				(font
					(size 1 1)
					(thickness 0.15)
				)
			)
		)
		(property "Manufacturer" "Murata"
			(at 0 0 90)
			(unlocked yes)
			(layer "F.Fab")
			(hide yes)
			(effects
				(font
					(size 1 1)
					(thickness 0.15)
				)
			)
		)
		(property "License" "Apache-2.0"
			(at 0 0 90)
			(unlocked yes)
			(layer "F.Fab")
			(hide yes)
			(effects
				(font
					(size 1 1)
					(thickness 0.15)
				)
			)
		)
		(property "Author" "Antmicro"
			(at 0 0 90)
			(unlocked yes)
			(layer "F.Fab")
			(hide yes)
			(effects
				(font
					(size 1 1)
					(thickness 0.15)
				)
			)
		)
		(property "Val" "100n"
			(at 0 0 90)
			(unlocked yes)
			(layer "F.Fab")
			(hide yes)
			(effects
				(font
					(size 1 1)
					(thickness 0.15)
				)
			)
		)
		(property "Voltage" "50V"
			(at 0 0 90)
			(unlocked yes)
			(layer "F.Fab")
			(hide yes)
			(effects
				(font
					(size 1 1)
					(thickness 0.15)
				)
			)
		)
		(property "Dielectric" "X5R"
			(at 0 0 90)
			(unlocked yes)
			(layer "F.Fab")
			(hide yes)
			(effects
				(font
					(size 1 1)
					(thickness 0.15)
				)
			)
		)
		(sheetname "/Compute module/")
		(sheetfile "compute-module.kicad_sch")
		(attr smd)
		(fp_rect
			(start -0.925 -0.47)
			(end 0.925 0.47)
			(stroke
				(width 0.05)
				(type default)
			)
			(fill no)
			(layer "F.CrtYd")
		)
		(fp_line
			(start 0.504 -0.25)
			(end 0.504 0.248)
			(stroke
				(width 0.15)
				(type solid)
			)
			(layer "F.Fab")
		)
		(fp_line
			(start -0.494 -0.25)
			(end 0.504 -0.25)
			(stroke
				(width 0.15)
				(type solid)
			)
			(layer "F.Fab")
		)
		(fp_line
			(start 0.504 0.248)
			(end -0.494 0.248)
			(stroke
				(width 0.15)
				(type solid)
			)
			(layer "F.Fab")
		)
		(fp_line
			(start -0.494 0.248)
			(end -0.494 -0.25)
			(stroke
				(width 0.15)
				(type solid)
			)
			(layer "F.Fab")
		)
		(fp_text user "Author: Antmicro"
			(at -0.939 3.399 90)
			(layer "F.Fab")
			(effects
				(font
					(size 0.7 0.7)
					(thickness 0.15)
				)
				(justify left bottom)
			)
		)
		(fp_text user "${REFERENCE}"
			(at -0.939 4.599 90)
			(layer "F.Fab")
			(effects
				(font
					(size 0.7 0.7)
					(thickness 0.15)
				)
				(justify left bottom)
			)
		)
		(fp_text user "License: Apache-2.0"
			(at -0.939 5.799 90)
			(layer "F.Fab")
			(effects
				(font
					(size 0.7 0.7)
					(thickness 0.15)
				)
				(justify left bottom)
			)
		)
		(pad "1" smd roundrect
			(at -0.48 0 90)
			(size 0.59 0.64)
			(layers "F.Cu" "F.Mask" "F.Paste")
			(roundrect_rratio 0.25)
			(net 3 "GND")
			(pintype "passive")
		)
		(pad "2" smd roundrect
			(at 0.48 0 90)
			(size 0.59 0.64)
			(layers "F.Cu" "F.Mask" "F.Paste")
			(roundrect_rratio 0.25)
			(net 9 "+3V3")
			(pintype "passive")
		)
	)
	(footprint "antmicro-footprints:R_0402_1005Metric"
		(layer "F.Cu")
		(at 123.792962 166.9165)
		(descr "Resistor SMD 0402")
		(tags "resistor SMD 0402")
		(property "Reference" "R509"
			(at -3.825 0.4 0)
			(layer "F.SilkS")
			(effects
				(font
					(size 0.7 0.7)
					(thickness 0.15)
				)
				(justify left bottom)
			)
		)
		(property "Value" "R_10k_0402"
			(at -1.011843 1.772047 0)
			(layer "F.Fab")
			(effects
				(font
					(size 0.7 0.7)
					(thickness 0.15)
				)
				(justify left bottom)
			)
		)
		(property "Datasheet" "https://www.bourns.com/docs/product-datasheets/cr.pdf"
			(at 0 0 0)
			(layer "F.Fab")
			(hide yes)
			(effects
				(font
					(size 1.27 1.27)
					(thickness 0.15)
				)
			)
		)
		(property "Manufacturer" "Bourns"
			(at 0 0 0)
			(unlocked yes)
			(layer "F.Fab")
			(hide yes)
			(effects
				(font
					(size 1 1)
					(thickness 0.15)
				)
			)
		)
		(property "MPN" "CR0402-FX-1002GLF"
			(at 0 0 0)
			(unlocked yes)
			(layer "F.Fab")
			(hide yes)
			(effects
				(font
					(size 1 1)
					(thickness 0.15)
				)
			)
		)
		(property "Val" "10k"
			(at 0 0 0)
			(unlocked yes)
			(layer "F.Fab")
			(hide yes)
			(effects
				(font
					(size 1 1)
					(thickness 0.15)
				)
			)
		)
		(property "License" "Apache-2.0"
			(at 0 0 0)
			(unlocked yes)
			(layer "F.Fab")
			(hide yes)
			(effects
				(font
					(size 1 1)
					(thickness 0.15)
				)
			)
		)
		(property "Author" "Antmicro"
			(at 0 0 0)
			(unlocked yes)
			(layer "F.Fab")
			(hide yes)
			(effects
				(font
					(size 1 1)
					(thickness 0.15)
				)
			)
		)
		(property "Tolerance" "1%"
			(at 0 0 0)
			(unlocked yes)
			(layer "F.Fab")
			(hide yes)
			(effects
				(font
					(size 1 1)
					(thickness 0.15)
				)
			)
		)
		(sheetname "/NVMe & microSD/")
		(sheetfile "nvme-micro-sd.kicad_sch")
		(attr smd)
		(fp_rect
			(start -0.925 -0.47)
			(end 0.925 0.47)
			(stroke
				(width 0.05)
				(type default)
			)
			(fill no)
			(layer "F.CrtYd")
		)
		(fp_rect
			(start -0.5 -0.25)
			(end 0.5 0.25)
			(stroke
				(width 0.15)
				(type solid)
			)
			(fill no)
			(layer "F.Fab")
		)
		(fp_text user "License: Apache-2.0"
			(at -0.95 5.169 0)
			(layer "F.Fab")
			(effects
				(font
					(size 0.7 0.7)
					(thickness 0.15)
				)
				(justify left bottom)
			)
		)
		(fp_text user "Author: Antmicro"
			(at -0.95 4.169 0)
			(layer "F.Fab")
			(effects
				(font
					(size 0.7 0.7)
					(thickness 0.15)
				)
				(justify left bottom)
			)
		)
		(fp_text user "${REFERENCE}"
			(at -0.95 3.168 0)
			(layer "F.Fab")
			(effects
				(font
					(size 0.7 0.7)
					(thickness 0.15)
				)
				(justify left bottom)
			)
		)
		(pad "1" smd roundrect
			(at -0.48 0)
			(size 0.59 0.64)
			(layers "F.Cu" "F.Mask" "F.Paste")
			(roundrect_rratio 0.25)
			(net 9 "+3V3")
			(pintype "passive")
		)
		(pad "2" smd roundrect
			(at 0.48 0)
			(size 0.59 0.64)
			(layers "F.Cu" "F.Mask" "F.Paste")
			(roundrect_rratio 0.25)
			(net 11 "/Compute module/SDIO.D3")
			(pintype "passive")
		)
	)
	(footprint "antmicro-footprints:TP_SMD_0.75mm"
		(layer "F.Cu")
		(at 118.142962 126.2415 180)
		(property "Reference" "TP503"
			(at -3.85 -0.5 0)
			(layer "F.SilkS")
			(effects
				(font
					(size 0.7 0.7)
					(thickness 0.15)
				)
				(justify right bottom)
			)
		)
		(property "Value" "TP_0.75mm_SMD"
			(at 0 1.2 0)
			(layer "F.Fab")
			(effects
				(font
					(size 0.7 0.7)
					(thickness 0.15)
				)
				(justify right bottom)
			)
		)
		(property "MPN" ""
			(at 0 0 180)
			(unlocked yes)
			(layer "F.Fab")
			(hide yes)
			(effects
				(font
					(size 1 1)
					(thickness 0.15)
				)
			)
		)
		(property "Manufacturer" ""
			(at 0 0 180)
			(unlocked yes)
			(layer "F.Fab")
			(hide yes)
			(effects
				(font
					(size 1 1)
					(thickness 0.15)
				)
			)
		)
		(property "Author" "Antmicro"
			(at 0 0 180)
			(unlocked yes)
			(layer "F.Fab")
			(hide yes)
			(effects
				(font
					(size 1 1)
					(thickness 0.15)
				)
			)
		)
		(property "License" "Apache-2.0"
			(at 0 0 180)
			(unlocked yes)
			(layer "F.Fab")
			(hide yes)
			(effects
				(font
					(size 1 1)
					(thickness 0.15)
				)
			)
		)
		(sheetname "/NVMe & microSD/")
		(sheetfile "nvme-micro-sd.kicad_sch")
		(attr exclude_from_pos_files exclude_from_bom)
		(fp_circle
			(center 0 0)
			(end 0.475 0)
			(stroke
				(width 0.05)
				(type default)
			)
			(fill no)
			(layer "F.CrtYd")
		)
		(fp_text user "Author: Antmicro"
			(at -0.4 3.901 180)
			(layer "F.Fab")
			(effects
				(font
					(size 0.7 0.7)
					(thickness 0.15)
				)
				(justify left bottom)
			)
		)
		(fp_text user "License: Apache-2.0"
			(at -0.4 5.101 180)
			(layer "F.Fab")
			(effects
				(font
					(size 0.7 0.7)
					(thickness 0.15)
				)
				(justify left bottom)
			)
		)
		(fp_text user "${REFERENCE}"
			(at -0.4 2.7 180)
			(layer "F.Fab")
			(effects
				(font
					(size 0.7 0.7)
					(thickness 0.15)
				)
				(justify left bottom)
			)
		)
		(pad "1" smd circle
			(at 0 0 180)
			(size 0.75 0.75)
			(layers "F.Cu" "F.Mask")
			(net 192 "Net-(J501-SMB_DATA)")
			(pinfunction "1")
			(pintype "passive")
		)
	)
)
